# S9S_MB_2U (Grand Teton) — schematic netlist excerpt (pin names and nets, part order shuffled) for the footprints in the layout excerpt that follows; sources: Cadence DE-HDL packaged netlist, KiCad conversion of 03242023_DA0F0TMBIJ0_F0T_Motherboard_J_brd_V01_OCP.brd

PC2088  Q_CAP  0.01UF 50V 10% EMPTY  pkg C0402  page 156 : A = P12V_OCP_SFF ; B = P12V_OCP_GATE_1
C1975  Q_CAP  1000PF 50V 5% EMPTY  pkg 0402  page 147 : A = GPU_HMC_PRSNT_ISO_N ; B = GND

(kicad_pcb
	(version 20260206)
	(generator "pcbnew")
	(generator_version "10.0")
	(general
		(thickness 1.6)
		(legacy_teardrops no)
	)
	(paper "A4")
	(title_block
		(title "03242023_DA0F0TMBIJ0_F0T_Motherboard_J_brd_V01_OCP.brd")
		(comment 1 "Grand Teton / footprints 3163-3164 of 6105")
	)
	(layers
		(0 "F.Cu" signal "TOP")
		(4 "In1.Cu" signal "GND")
		(6 "In2.Cu" signal "IN1")
		(8 "In3.Cu" signal "GND1")
		(10 "In4.Cu" signal "IN2")
		(12 "In5.Cu" signal "GND2")
		(14 "In6.Cu" signal "IN3")
		(16 "In7.Cu" signal "GND3")
		(18 "In8.Cu" signal "VCC")
		(20 "In9.Cu" signal "VCC1")
		(22 "In10.Cu" signal "GND4")
		(24 "In11.Cu" signal "IN4")
		(26 "In12.Cu" signal "GND5")
		(28 "In13.Cu" signal "IN5")
		(30 "In14.Cu" signal "GND6")
		(32 "In15.Cu" signal "IN6")
		(34 "In16.Cu" signal "GND7")
		(2 "B.Cu" signal "BOTTOM")
		(9 "F.Adhes" user "F.Adhesive")
		(11 "B.Adhes" user "B.Adhesive")
		(13 "F.Paste" user "Package Geometry/Pastemask Top")
		(15 "B.Paste" user "Package Geometry/Pastemask Bottom")
		(5 "F.SilkS" user "Ref Des/Silkscreen Top")
		(7 "B.SilkS" user "Ref Des/Silkscreen Bottom")
		(1 "F.Mask" user "Board Geometry/Soldermask Top")
		(3 "B.Mask" user "Board Geometry/Soldermask Bottom")
		(17 "Dwgs.User" user "User.Drawings")
		(19 "Cmts.User" user "User.Comments")
		(21 "Eco1.User" user "User.Eco1")
		(23 "Eco2.User" user "User.Eco2")
		(25 "Edge.Cuts" user "Board Geometry/Outline")
		(27 "Margin" user)
		(31 "F.CrtYd" user "Package Geometry/Place Bound Top")
		(29 "B.CrtYd" user "Package Geometry/Place Bound Bottom")
		(35 "F.Fab" user "Ref Des/Assembly Top")
		(33 "B.Fab" user "Ref Des/Assembly Bottom")
	)
	(footprint ""
		(layer "F.Cu")
		(at 176.078388 -417.745418)
		(property "Reference" "C1975"
			(at 0 0 0)
			(layer "F.SilkS")
			(hide yes)
			(effects
				(font
					(size 1.27 1.27)
				)
			)
		)
		(property "Value" ""
			(at 0 0 0)
			(layer "F.Fab")
			(effects
				(font
					(size 1.27 1.27)
				)
			)
		)
		(duplicate_pad_numbers_are_jumpers no)
		(fp_line
			(start -0.7874 -0.4064)
			(end 0.7874 -0.4064)
			(stroke
				(width 0.1524)
				(type default)
			)
			(layer "F.SilkS")
		)
		(fp_line
			(start -0.7874 0.4064)
			(end -0.7874 -0.4064)
			(stroke
				(width 0.1524)
				(type default)
			)
			(layer "F.SilkS")
		)
		(fp_line
			(start 0.7874 -0.4064)
			(end 0.7874 0.4064)
			(stroke
				(width 0.1524)
				(type default)
			)
			(layer "F.SilkS")
		)
		(fp_line
			(start 0.7874 0.4064)
			(end -0.7874 0.4064)
			(stroke
				(width 0.1524)
				(type default)
			)
			(layer "F.SilkS")
		)
		(fp_line
			(start -0.67945 -0.305054)
			(end -0.12065 -0.305054)
			(stroke
				(width 0.1)
				(type default)
			)
			(layer "F.Fab")
		)
		(fp_line
			(start -0.67945 0.3048)
			(end -0.67945 -0.305054)
			(stroke
				(width 0.1)
				(type default)
			)
			(layer "F.Fab")
		)
		(fp_line
			(start -0.12065 -0.305054)
			(end -0.12065 -0.2794)
			(stroke
				(width 0.1)
				(type default)
			)
			(layer "F.Fab")
		)
		(fp_line
			(start -0.12065 -0.2794)
			(end 0.12065 -0.2794)
			(stroke
				(width 0.1)
				(type default)
			)
			(layer "F.Fab")
		)
		(fp_line
			(start -0.12065 0.2794)
			(end -0.12065 0.3048)
			(stroke
				(width 0.1)
				(type default)
			)
			(layer "F.Fab")
		)
		(fp_line
			(start -0.12065 0.3048)
			(end -0.67945 0.3048)
			(stroke
				(width 0.1)
				(type default)
			)
			(layer "F.Fab")
		)
		(fp_line
			(start 0.120396 0.2794)
			(end -0.12065 0.2794)
			(stroke
				(width 0.1)
				(type default)
			)
			(layer "F.Fab")
		)
		(fp_line
			(start 0.120396 0.3048)
			(end 0.120396 0.2794)
			(stroke
				(width 0.1)
				(type default)
			)
			(layer "F.Fab")
		)
		(fp_line
			(start 0.12065 -0.3048)
			(end 0.67945 -0.3048)
			(stroke
				(width 0.1)
				(type default)
			)
			(layer "F.Fab")
		)
		(fp_line
			(start 0.12065 -0.2794)
			(end 0.12065 -0.3048)
			(stroke
				(width 0.1)
				(type default)
			)
			(layer "F.Fab")
		)
		(fp_line
			(start 0.67945 -0.3048)
			(end 0.67945 0.3048)
			(stroke
				(width 0.1)
				(type default)
			)
			(layer "F.Fab")
		)
		(fp_line
			(start 0.67945 0.3048)
			(end 0.120396 0.3048)
			(stroke
				(width 0.1)
				(type default)
			)
			(layer "F.Fab")
		)
		(pad "1" smd circle
			(at -0.40005 0)
			(size 0 0)
			(layers "F.Cu" "F.Mask" "F.Paste")
			(net "GPU_HMC_PRSNT_ISO_N")
		)
		(pad "2" smd circle
			(at 0.40005 0)
			(size 0 0)
			(layers "F.Cu" "F.Mask" "F.Paste")
			(net "GND")
		)
	)
	(footprint ""
		(layer "F.Cu")
		(at 453.054212 -24.619458 180)
		(property "Reference" "PC2088"
			(at 0 0 180)
			(layer "F.SilkS")
			(hide yes)
			(effects
				(font
					(size 1.27 1.27)
				)
			)
		)
		(property "Value" ""
			(at 0 0 180)
			(layer "F.Fab")
			(effects
				(font
					(size 1.27 1.27)
				)
			)
		)
		(duplicate_pad_numbers_are_jumpers no)
		(fp_line
			(start 0.7874 0.4064)
			(end -0.7874 0.4064)
			(stroke
				(width 0.1524)
				(type default)
			)
			(layer "F.SilkS")
		)
		(fp_line
			(start 0.7874 -0.4064)
			(end 0.7874 0.4064)
			(stroke
				(width 0.1524)
				(type default)
			)
			(layer "F.SilkS")
		)
		(fp_line
			(start -0.7874 0.4064)
			(end -0.7874 -0.4064)
			(stroke
				(width 0.1524)
				(type default)
			)
			(layer "F.SilkS")
		)
		(fp_line
			(start -0.7874 -0.4064)
			(end 0.7874 -0.4064)
			(stroke
				(width 0.1524)
				(type default)
			)
			(layer "F.SilkS")
		)
		(fp_line
			(start 0.67945 0.3048)
			(end 0.120396 0.3048)
			(stroke
				(width 0.1)
				(type default)
			)
			(layer "F.Fab")
		)
		(fp_line
			(start 0.67945 -0.3048)
			(end 0.67945 0.3048)
			(stroke
				(width 0.1)
				(type default)
			)
			(layer "F.Fab")
		)
		(fp_line
			(start 0.12065 -0.2794)
			(end 0.12065 -0.3048)
			(stroke
				(width 0.1)
				(type default)
			)
			(layer "F.Fab")
		)
		(fp_line
			(start 0.12065 -0.3048)
			(end 0.67945 -0.3048)
			(stroke
				(width 0.1)
				(type default)
			)
			(layer "F.Fab")
		)
		(fp_line
			(start 0.120396 0.3048)
			(end 0.120396 0.2794)
			(stroke
				(width 0.1)
				(type default)
			)
			(layer "F.Fab")
		)
		(fp_line
			(start 0.120396 0.2794)
			(end -0.12065 0.2794)
			(stroke
				(width 0.1)
				(type default)
			)
			(layer "F.Fab")
		)
		(fp_line
			(start -0.12065 0.3048)
			(end -0.67945 0.3048)
			(stroke
				(width 0.1)
				(type default)
			)
			(layer "F.Fab")
		)
		(fp_line
			(start -0.12065 0.2794)
			(end -0.12065 0.3048)
			(stroke
				(width 0.1)
				(type default)
			)
			(layer "F.Fab")
		)
		(fp_line
			(start -0.12065 -0.2794)
			(end 0.12065 -0.2794)
			(stroke
				(width 0.1)
				(type default)
			)
			(layer "F.Fab")
		)
		(fp_line
			(start -0.12065 -0.305054)
			(end -0.12065 -0.2794)
			(stroke
				(width 0.1)
				(type default)
			)
			(layer "F.Fab")
		)
		(fp_line
			(start -0.67945 0.3048)
			(end -0.67945 -0.305054)
			(stroke
				(width 0.1)
				(type default)
			)
			(layer "F.Fab")
		)
		(fp_line
			(start -0.67945 -0.305054)
			(end -0.12065 -0.305054)
			(stroke
				(width 0.1)
				(type default)
			)
			(layer "F.Fab")
		)
		(pad "1" smd circle
			(at -0.40005 0 180)
			(size 0 0)
			(layers "F.Cu" "F.Mask" "F.Paste")
			(net "P12V_OCP_SFF")
		)
		(pad "2" smd circle
			(at 0.40005 0 180)
			(size 0 0)
			(layers "F.Cu" "F.Mask" "F.Paste")
			(net "P12V_OCP_GATE_1")
		)
	)
)
